G04 ================== begin FILE IDENTIFICATION RECORD ==================*
G04 Layout Name:  t6m_pdb_d_0928_1400_274.brd*
G04 Film Name:    smb.art*
G04 File Format:  Gerber RS274X*
G04 File Origin:  Cadence Allegro 16.3-S048*
G04 Origin Date:  Tue Nov 26 11:01:50 2013*
G04 *
G04 Layer:  DRAWING FORMAT/TITLE_BLOCK*
G04 Layer:  VIA CLASS/SOLDERMASK_BOTTOM*
G04 Layer:  PIN/SOLDERMASK_BOTTOM*
G04 Layer:  PACKAGE GEOMETRY/SOLDERMASK_BOTTOM*
G04 Layer:  MANUFACTURING/PHOTOPLOT_OUTLINE*
G04 Layer:  DRAWING FORMAT/TITLE_DATA_SMB*
G04 Layer:  BOARD GEOMETRY/SOLDERMASK_BOTTOM*
G04 *
G04 Offset:    (0.00 0.00)*
G04 Mirror:    No*
G04 Mode:      Positive*
G04 Rotation:  0*
G04 FullContactRelief:  No*
G04 UndefLineWidth:     6.00*
G04 ================== end FILE IDENTIFICATION RECORD ====================*
%FSLAX25Y25*MOIN*%
%IR0*IPPOS*OFA0.00000B0.00000*MIA0B0*SFA1.00000B1.00000*%
%ADD23C,.03*%
%ADD32C,.05*%
%ADD25C,.034*%
%ADD18C,.044*%
%ADD22C,.081*%
%ADD16C,.064*%
%ADD13C,.056*%
%ADD31R,.05X.05*%
%ADD28C,.068*%
%ADD10C,.059*%
%ADD20R,.044X.044*%
%ADD24R,.081X.081*%
%ADD15C,.097*%
%ADD17R,.064X.064*%
%ADD21R,.056X.056*%
%ADD29R,.068X.068*%
%ADD12R,.059X.059*%
%ADD34O,.225X.264*%
%ADD19C,.115*%
%ADD11C,.152*%
%ADD33C,.225*%
%ADD27C,.118*%
%ADD35C,.335*%
%ADD30C,.119*%
%ADD14C,.146*%
%ADD26C,.178*%
%ADD36C,.02*%
%ADD37C,.006*%
%ADD38C,.194*%
G75*
%LPD*%
G75*
G36*
G01X65354Y95060D02*
G02I0J19900D01*
G37*
G36*
G01Y445060D02*
G02I0J19900D01*
G37*
G36*
G01Y795060D02*
G02I0J19900D01*
G37*
G36*
G01Y1145060D02*
G02I0J19900D01*
G37*
G36*
G01Y1495060D02*
G02I0J19900D01*
G37*
G36*
G01Y1845060D02*
G02I0J19900D01*
G37*
G36*
G01X61058Y882277D02*
G03I-5900J0D01*
G37*
G36*
G01X326986Y127165D02*
G02I-19900J0D01*
G37*
G36*
G01Y477165D02*
G02I-19900J0D01*
G37*
G36*
G01Y827165D02*
G02I-19900J0D01*
G37*
G36*
G01Y1343504D02*
G02I-19900J0D01*
G37*
G36*
G01Y1693504D02*
G02I-19900J0D01*
G37*
G36*
G01X326987Y2043503D02*
G02I-19900J0D01*
G37*
G36*
G01X350726Y2035270D02*
G03I-5900J0D01*
G37*
G36*
G01X395472Y66182D02*
G03I-5900J0D01*
G37*
%LPC*%
G75*
G54D38*
X65354Y114960D03*
Y464960D03*
Y814960D03*
Y1164960D03*
Y1514960D03*
Y1864960D03*
X307086Y127165D03*
Y477165D03*
Y827165D03*
Y1343504D03*
Y1693504D03*
X307087Y2043503D03*
%LPD*%
G75*
G54D10*
X17735Y24953D03*
X27735D03*
X22735Y34953D03*
Y216976D03*
X27735Y206976D03*
X17735Y233811D03*
X27735D03*
X22735Y243811D03*
X27735Y415834D03*
X22735Y425834D03*
Y1957291D03*
X27735Y1947291D03*
X22735Y2061661D03*
X27735Y2051661D03*
X37735Y24953D03*
X47735D03*
X32735Y34953D03*
X42735D03*
Y216976D03*
X32735D03*
X47735Y206976D03*
X37735D03*
Y233811D03*
X47735D03*
X32735Y243811D03*
X42735D03*
X47735Y415834D03*
X37735D03*
X42735Y425834D03*
X32735D03*
X42735Y1957291D03*
X32735D03*
X47735Y1947291D03*
X37735D03*
X42735Y2061661D03*
X32735D03*
X47735Y2051661D03*
X37735D03*
X52735Y216976D03*
Y425834D03*
Y1957291D03*
Y2061661D03*
X189762Y73105D03*
X190289Y152050D03*
X190357Y247568D03*
X190817Y331786D03*
X189761Y421732D03*
X190553Y506517D03*
X192888Y598130D03*
X190816Y681645D03*
X191846Y774526D03*
X191606Y856244D03*
X196311Y947202D03*
X195516Y1032544D03*
X191250Y1122856D03*
X191342Y1206233D03*
X191846Y1299104D03*
X190552Y1380966D03*
X189463Y1474162D03*
X191079Y1557277D03*
X192143Y1648177D03*
X191607Y1731351D03*
X191530Y1823227D03*
X190289Y1900420D03*
X192125Y1998730D03*
X191530Y2043388D03*
G54D11*
X12735Y59953D03*
Y181976D03*
Y268811D03*
Y390834D03*
Y1922291D03*
Y2026661D03*
X57735Y59953D03*
Y181976D03*
Y268811D03*
Y390834D03*
Y1922291D03*
Y2026661D03*
G54D20*
X25389Y1030199D03*
X25393Y1388464D03*
G54D30*
X163385Y27205D03*
Y202205D03*
Y377205D03*
X163386Y552205D03*
Y727205D03*
X163385Y902205D03*
Y1077205D03*
Y1252205D03*
Y1427205D03*
Y1602205D03*
Y1777205D03*
Y1952205D03*
X373385Y32520D03*
Y207520D03*
Y382520D03*
X373386Y557520D03*
Y732520D03*
X373385Y907520D03*
Y1082520D03*
Y1257520D03*
Y1432520D03*
Y1607520D03*
Y1782520D03*
Y1957520D03*
G54D12*
X17735Y206976D03*
Y415834D03*
Y1947291D03*
Y2051661D03*
X52735Y34953D03*
Y243811D03*
X203542Y73105D03*
X204069Y152050D03*
X204137Y247568D03*
X204597Y331786D03*
X203541Y421732D03*
X204333Y506517D03*
X206668Y598130D03*
X204596Y681645D03*
X205626Y774526D03*
X205386Y856244D03*
X210091Y947202D03*
X209296Y1032544D03*
X205030Y1122856D03*
X205122Y1206233D03*
X205626Y1299104D03*
X204332Y1380966D03*
X203243Y1474162D03*
X204859Y1557277D03*
X205923Y1648177D03*
X205387Y1731351D03*
X205310Y1823227D03*
X204069Y1900420D03*
X205905Y1998730D03*
X205310Y2043388D03*
G54D21*
X18995Y1612992D03*
X53995Y518701D03*
G54D31*
X173385Y32520D03*
Y207520D03*
Y382520D03*
X173386Y557520D03*
Y732520D03*
X173385Y907520D03*
Y1082520D03*
Y1257520D03*
Y1432520D03*
Y1607520D03*
Y1782520D03*
Y1957520D03*
G54D13*
X18995Y508701D03*
X23995Y518701D03*
X21495Y559882D03*
X11692D03*
X21495Y1571811D03*
X11692D03*
X23995Y1622992D03*
X28995Y508701D03*
X38995D03*
X48995D03*
X33995Y518701D03*
X43995D03*
X51495Y559882D03*
Y1571811D03*
X43995Y1622992D03*
X33995D03*
X48995Y1612992D03*
X38995D03*
X28995D03*
X61298Y559882D03*
Y1571811D03*
X53995Y1622992D03*
G54D22*
X23402Y1668874D03*
Y1685410D03*
Y1701945D03*
Y1718480D03*
Y1735016D03*
Y1751551D03*
Y1768087D03*
Y1784622D03*
Y1817693D03*
Y1801158D03*
X45056Y1668874D03*
Y1685410D03*
Y1701945D03*
Y1718480D03*
Y1735016D03*
Y1751551D03*
Y1768087D03*
Y1784622D03*
Y1801158D03*
G54D14*
X13995Y543701D03*
Y1587992D03*
X58995Y543701D03*
Y1587992D03*
G54D32*
X173385Y21890D03*
X183385Y32520D03*
Y21890D03*
X193385Y32520D03*
Y21890D03*
X173385Y196890D03*
X183385D03*
X193385D03*
X183385Y207520D03*
X193385D03*
X173385Y371890D03*
X183385D03*
X193385D03*
X183385Y382520D03*
X193385D03*
X173386Y546890D03*
X183386Y557520D03*
Y546890D03*
X193386Y557520D03*
Y546890D03*
X173386Y721890D03*
X183386Y732520D03*
Y721890D03*
X193386Y732520D03*
Y721890D03*
X173385Y896890D03*
X183385D03*
X193385D03*
X183385Y907520D03*
X193385D03*
X173385Y1071890D03*
X183385D03*
X193385D03*
X183385Y1082520D03*
X193385D03*
X173385Y1246890D03*
X183385Y1257520D03*
Y1246890D03*
X193385Y1257520D03*
Y1246890D03*
X173385Y1421890D03*
X183385Y1432520D03*
Y1421890D03*
X193385Y1432520D03*
Y1421890D03*
X173385Y1596890D03*
X183385D03*
X193385D03*
X183385Y1607520D03*
X193385D03*
X173385Y1771890D03*
X183385D03*
X193385D03*
X183385Y1782520D03*
X193385D03*
X173385Y1946890D03*
X183385Y1957520D03*
Y1946890D03*
X193385Y1957520D03*
Y1946890D03*
X203385Y32520D03*
Y21890D03*
X213385Y32520D03*
Y21890D03*
X203385Y196890D03*
X213385D03*
X203385Y207520D03*
X213385D03*
X203385Y371890D03*
X213385D03*
X203385Y382520D03*
X213385D03*
X203386Y557520D03*
Y546890D03*
X213386Y557520D03*
Y546890D03*
X203386Y732520D03*
Y721890D03*
X213386Y732520D03*
Y721890D03*
X203385Y896890D03*
X213385D03*
X203385Y907520D03*
X213385D03*
X203385Y1071890D03*
X213385D03*
X203385Y1082520D03*
X213385D03*
X203385Y1257520D03*
Y1246890D03*
X213385Y1257520D03*
Y1246890D03*
X203385Y1432520D03*
Y1421890D03*
X213385Y1432520D03*
Y1421890D03*
X203385Y1596890D03*
X213385D03*
X203385Y1607520D03*
X213385D03*
X203385Y1771890D03*
X213385D03*
X203385Y1782520D03*
X213385D03*
X203385Y1957520D03*
Y1946890D03*
X213385Y1957520D03*
Y1946890D03*
X223385Y32520D03*
Y21890D03*
X233385Y32520D03*
Y21890D03*
X243385Y32520D03*
Y21890D03*
X223385Y196890D03*
X233385D03*
X243385D03*
X223385Y207520D03*
X233385D03*
X243385D03*
X223385Y371890D03*
X233385D03*
X243385D03*
X223385Y382520D03*
X233385D03*
X243385D03*
X223386Y557520D03*
Y546890D03*
X233386Y557520D03*
Y546890D03*
X243386Y557520D03*
Y546890D03*
X223386Y732520D03*
Y721890D03*
X233386Y732520D03*
Y721890D03*
X243386Y732520D03*
Y721890D03*
X223385Y896890D03*
X233385D03*
X243385D03*
X223385Y907520D03*
X233385D03*
X243385D03*
X223385Y1071890D03*
X233385D03*
X243385D03*
X223385Y1082520D03*
X233385D03*
X243385D03*
X223385Y1257520D03*
Y1246890D03*
X233385Y1257520D03*
Y1246890D03*
X243385Y1257520D03*
Y1246890D03*
X223385Y1432520D03*
Y1421890D03*
X233385Y1432520D03*
Y1421890D03*
X243385Y1432520D03*
Y1421890D03*
X223385Y1596890D03*
X233385D03*
X243385D03*
X223385Y1607520D03*
X233385D03*
X243385D03*
X223385Y1771890D03*
X233385D03*
X243385D03*
X223385Y1782520D03*
X233385D03*
X243385D03*
X223385Y1957520D03*
Y1946890D03*
X233385Y1957520D03*
Y1946890D03*
X243385Y1957520D03*
Y1946890D03*
X253385Y21890D03*
Y32520D03*
X263385Y21890D03*
Y32520D03*
X253385Y196890D03*
X263385D03*
X253385Y207520D03*
X263385D03*
X253385Y371890D03*
X263385D03*
X253385Y382520D03*
X263385D03*
X253386Y546890D03*
Y557520D03*
X263386Y546890D03*
Y557520D03*
X253386Y721890D03*
Y732520D03*
X263386Y721890D03*
Y732520D03*
X253385Y896890D03*
X263385D03*
X253385Y907520D03*
X263385D03*
X253385Y1071890D03*
X263385D03*
X253385Y1082520D03*
X263385D03*
X253385Y1246890D03*
Y1257520D03*
X263385Y1246890D03*
Y1257520D03*
X253385Y1421890D03*
Y1432520D03*
X263385Y1421890D03*
Y1432520D03*
X253385Y1596890D03*
X263385D03*
X253385Y1607520D03*
X263385D03*
X253385Y1771890D03*
X263385D03*
X253385Y1782520D03*
X263385D03*
X253385Y1946890D03*
Y1957520D03*
X263385Y1946890D03*
Y1957520D03*
X273385Y21890D03*
Y32520D03*
X283385Y21890D03*
Y32520D03*
X273385Y196890D03*
X283385D03*
X273385Y207520D03*
X283385D03*
X273385Y371890D03*
X283385D03*
X273385Y382520D03*
X283385D03*
X273386Y546890D03*
Y557520D03*
X283386Y546890D03*
Y557520D03*
X273386Y721890D03*
Y732520D03*
X283386Y721890D03*
Y732520D03*
X273385Y896890D03*
X283385D03*
X273385Y907520D03*
X283385D03*
X273385Y1071890D03*
X283385D03*
X273385Y1082520D03*
X283385D03*
X273385Y1246890D03*
Y1257520D03*
X283385Y1246890D03*
Y1257520D03*
X273385Y1421890D03*
Y1432520D03*
X283385Y1421890D03*
Y1432520D03*
X273385Y1596890D03*
X283385D03*
X273385Y1607520D03*
X283385D03*
X273385Y1771890D03*
X283385D03*
X273385Y1782520D03*
X283385D03*
X273385Y1946890D03*
Y1957520D03*
X283385Y1946890D03*
Y1957520D03*
X293385Y21890D03*
Y32520D03*
X303385Y21890D03*
Y32520D03*
X313385D03*
Y21890D03*
X293385Y196890D03*
X303385D03*
X313385D03*
X293385Y207520D03*
X303385D03*
X313385D03*
X293385Y371890D03*
X303385D03*
X313385D03*
X293385Y382520D03*
X303385D03*
X313385D03*
X293386Y546890D03*
Y557520D03*
X303386Y546890D03*
Y557520D03*
X313386D03*
Y546890D03*
X293386Y721890D03*
Y732520D03*
X303386Y721890D03*
Y732520D03*
X313386D03*
Y721890D03*
X293385Y896890D03*
X303385D03*
X313385D03*
X293385Y907520D03*
X303385D03*
X313385D03*
X293385Y1071890D03*
X303385D03*
X313385D03*
X293385Y1082520D03*
X303385D03*
X313385D03*
X293385Y1246890D03*
Y1257520D03*
X303385Y1246890D03*
Y1257520D03*
X313385D03*
Y1246890D03*
X293385Y1421890D03*
Y1432520D03*
X303385Y1421890D03*
Y1432520D03*
X313385D03*
Y1421890D03*
X293385Y1596890D03*
X303385D03*
X313385D03*
X293385Y1607520D03*
X303385D03*
X313385D03*
X293385Y1771890D03*
X303385D03*
X313385D03*
X293385Y1782520D03*
X303385D03*
X313385D03*
X293385Y1946890D03*
Y1957520D03*
X303385Y1946890D03*
Y1957520D03*
X313385D03*
Y1946890D03*
X337165Y24705D03*
X323385Y32520D03*
Y21890D03*
X337165Y34705D03*
Y199705D03*
X323385Y196890D03*
X337165Y209705D03*
X323385Y207520D03*
Y371890D03*
X337165Y374705D03*
Y384705D03*
X323385Y382520D03*
X337166Y549705D03*
Y559705D03*
X323386Y557520D03*
Y546890D03*
X337166Y724705D03*
X323386Y732520D03*
Y721890D03*
X337166Y734705D03*
X337165Y899705D03*
X323385Y896890D03*
X337165Y909705D03*
X323385Y907520D03*
Y1071890D03*
X337165Y1074705D03*
Y1084705D03*
X323385Y1082520D03*
X337165Y1249705D03*
Y1259705D03*
X323385Y1257520D03*
Y1246890D03*
X337165Y1424705D03*
Y1434705D03*
X323385Y1432520D03*
Y1421890D03*
X337165Y1599705D03*
X323385Y1596890D03*
X337165Y1609705D03*
X323385Y1607520D03*
Y1771890D03*
X337165Y1774705D03*
Y1784705D03*
X323385Y1782520D03*
X337165Y1949705D03*
Y1959705D03*
X323385Y1957520D03*
Y1946890D03*
X342165Y19705D03*
Y29705D03*
X347165Y24705D03*
X352165Y19705D03*
Y29705D03*
X357165Y24705D03*
X362165Y19705D03*
Y29705D03*
X347165Y34705D03*
X357165D03*
X342165Y194705D03*
X347165Y199705D03*
X352165Y194705D03*
X357165Y199705D03*
X362165Y194705D03*
X342165Y204705D03*
X347165Y209705D03*
X352165Y204705D03*
X357165Y209705D03*
X362165Y204705D03*
X342165Y369705D03*
X352165D03*
X362165D03*
X342165Y379705D03*
X347165Y374705D03*
Y384705D03*
X352165Y379705D03*
X357165Y374705D03*
Y384705D03*
X362165Y379705D03*
X342166Y544705D03*
Y554705D03*
X347166Y549705D03*
Y559705D03*
X352166Y544705D03*
Y554705D03*
X357166Y549705D03*
Y559705D03*
X362166Y544705D03*
Y554705D03*
X342166Y719705D03*
Y729705D03*
X347166Y724705D03*
X352166Y719705D03*
Y729705D03*
X357166Y724705D03*
X362166Y719705D03*
Y729705D03*
X347166Y734705D03*
X357166D03*
X342165Y894705D03*
X347165Y899705D03*
X352165Y894705D03*
X357165Y899705D03*
X362165Y894705D03*
X342165Y904705D03*
X347165Y909705D03*
X352165Y904705D03*
X357165Y909705D03*
X362165Y904705D03*
X342165Y1069705D03*
X352165D03*
X362165D03*
X342165Y1079705D03*
X347165Y1074705D03*
Y1084705D03*
X352165Y1079705D03*
X357165Y1074705D03*
Y1084705D03*
X362165Y1079705D03*
X342165Y1244705D03*
Y1254705D03*
X347165Y1249705D03*
Y1259705D03*
X352165Y1244705D03*
Y1254705D03*
X357165Y1249705D03*
Y1259705D03*
X362165Y1244705D03*
Y1254705D03*
X342165Y1419705D03*
Y1429705D03*
X347165Y1424705D03*
Y1434705D03*
X352165Y1419705D03*
Y1429705D03*
X357165Y1424705D03*
Y1434705D03*
X362165Y1419705D03*
Y1429705D03*
X342165Y1594705D03*
X347165Y1599705D03*
X352165Y1594705D03*
X357165Y1599705D03*
X362165Y1594705D03*
X342165Y1604705D03*
X347165Y1609705D03*
X352165Y1604705D03*
X357165Y1609705D03*
X362165Y1604705D03*
X342165Y1769705D03*
X352165D03*
X362165D03*
X342165Y1779705D03*
X347165Y1774705D03*
Y1784705D03*
X352165Y1779705D03*
X357165Y1774705D03*
Y1784705D03*
X362165Y1779705D03*
X342165Y1944705D03*
Y1954705D03*
X347165Y1949705D03*
Y1959705D03*
X352165Y1944705D03*
Y1954705D03*
X357165Y1949705D03*
Y1959705D03*
X362165Y1944705D03*
Y1954705D03*
G54D23*
X49441Y1238962D03*
X46980Y1335843D03*
Y1325843D03*
Y1315843D03*
Y1320843D03*
Y1330843D03*
Y1345843D03*
Y1340843D03*
X61888Y666012D03*
X57124Y675327D03*
X54483Y679810D03*
X59236Y670758D03*
X70865Y854278D03*
Y872278D03*
Y866278D03*
Y860278D03*
Y897750D03*
Y890116D03*
X61866Y1309190D03*
X67568Y1307829D03*
X54543Y1308995D03*
X61866Y1342104D03*
X95775Y751469D03*
X92216Y899865D03*
X90708Y878615D03*
X92633Y907404D03*
X92989Y927334D03*
X98139Y990959D03*
X82763Y1060051D03*
X96684Y1081791D03*
X96510Y1395382D03*
X106958Y26285D03*
X107405Y49898D03*
X107037Y34687D03*
X106836Y376461D03*
X106709Y391219D03*
X107025Y725368D03*
X106935Y745139D03*
X107173Y735219D03*
X100687Y999391D03*
X107351Y1093484D03*
X107235Y1081791D03*
X107215Y1072208D03*
X105152Y1118381D03*
X100719Y1312810D03*
Y1306810D03*
Y1330810D03*
Y1336810D03*
Y1324810D03*
Y1318810D03*
Y1346065D03*
X101626Y1397635D03*
X106962Y1434041D03*
X106921Y1419492D03*
X106763Y1444599D03*
X107006Y1452651D03*
X107355Y1770437D03*
X107220Y1791589D03*
X107373Y1780544D03*
X106819Y1802230D03*
X144878Y1738861D03*
X157558Y51426D03*
X156865Y401207D03*
X156610Y751063D03*
X156854Y1101031D03*
X158618Y1399448D03*
X164037Y1400226D03*
X170351Y1401324D03*
X159192Y1451105D03*
X150309Y1737009D03*
X168151Y1739208D03*
X156183Y1735240D03*
X165782Y1732903D03*
X163257Y1737619D03*
X156452Y1800821D03*
X175989Y944537D03*
X176011Y936829D03*
X175359Y963486D03*
X175561Y955964D03*
X175135Y972490D03*
X175022Y980281D03*
X175742Y989958D03*
X175449Y997660D03*
X175698Y1008730D03*
X175473Y1016296D03*
X175448Y1031766D03*
X175897Y1023997D03*
X176083Y1402321D03*
X173394Y1736051D03*
X256947Y128276D03*
X257125Y115559D03*
X265722Y463102D03*
X265737Y473680D03*
X255837Y823626D03*
X255687Y812192D03*
X283086Y162675D03*
X271547Y245353D03*
X281193Y241624D03*
X281074Y337688D03*
X289895D03*
X291002Y417844D03*
X281569Y421169D03*
X278405Y512341D03*
X269516D03*
X285348Y595540D03*
X270109Y687192D03*
X278955D03*
X273114Y770968D03*
X282737Y767643D03*
X272181Y862354D03*
X281305Y862237D03*
X275966Y944767D03*
X285874Y941442D03*
X281124Y1031162D03*
X290107D03*
X282958Y1119471D03*
X289082Y1206777D03*
X279559D03*
X283808Y1293959D03*
X279518Y1389543D03*
X270579Y1389626D03*
X270234Y1467760D03*
X279990Y1464435D03*
X285054Y1558211D03*
X284086Y1644883D03*
X274704Y1738196D03*
X284583Y1738465D03*
X281066Y1819569D03*
X291550Y1814846D03*
X280240Y1858668D03*
X279976Y1864565D03*
X282717Y1913327D03*
X273817D03*
X304151Y63778D03*
X313089D03*
X294483Y67732D03*
X291943Y162630D03*
X308057Y248863D03*
X306267Y241010D03*
X314914Y238162D03*
X314940Y252083D03*
X305867Y258589D03*
X295509Y592215D03*
X309678Y1053262D03*
X292698Y1116146D03*
X312527Y1162266D03*
X312698Y1172804D03*
X294133Y1290634D03*
X314183Y1403423D03*
X302267Y1524401D03*
X301734Y1513883D03*
X312077Y1575871D03*
X294392Y1558211D03*
X294090Y1641558D03*
X311539Y1753499D03*
X314562Y1994087D03*
X331403Y51409D03*
X333889Y56021D03*
X338227Y61559D03*
X322005Y63778D03*
X320372Y225979D03*
X318088Y231820D03*
X321899Y238137D03*
X329930Y245684D03*
X331046Y232021D03*
X320961Y250105D03*
X324709Y231580D03*
X335522Y404033D03*
X323313Y418313D03*
X326196Y413982D03*
X328950Y409216D03*
X320980Y423225D03*
X336617Y577978D03*
X319305Y582111D03*
X329636Y584715D03*
X317724Y588250D03*
X337387Y586230D03*
X320380Y576491D03*
X331867Y589810D03*
X333750Y595326D03*
X323751Y589155D03*
X319852Y593330D03*
X321742Y599041D03*
X331568Y752967D03*
X339012Y752859D03*
X329336Y762693D03*
X334010Y758588D03*
X327524Y758020D03*
X339615Y926357D03*
X329938Y948756D03*
X332527Y943746D03*
X324098Y946104D03*
X318557Y941178D03*
X323868Y929978D03*
X326646Y939788D03*
X333300Y928464D03*
X336160Y937262D03*
X328583Y933262D03*
X321425Y951577D03*
X324246Y1051786D03*
X335677Y1048904D03*
X317592Y1053050D03*
X331920Y1116088D03*
X337509Y1109598D03*
X328989Y1121090D03*
X326558Y1126368D03*
X327452Y1279447D03*
X321978Y1282086D03*
X338047Y1282599D03*
X333242Y1276809D03*
X329619Y1284016D03*
X327932Y1289221D03*
X319404Y1401346D03*
X325636Y1399114D03*
X334646Y1400804D03*
X323720Y1570924D03*
X329399Y1571939D03*
X317243Y1574832D03*
X333474Y1566686D03*
X335963Y1573797D03*
X329887Y1752081D03*
X321283Y1753466D03*
X335730Y1753270D03*
X338309Y1927623D03*
X332399Y1926787D03*
X324803Y1990272D03*
X359931Y52189D03*
X348289Y50863D03*
X345089Y56190D03*
X340373Y51579D03*
X342097Y401684D03*
X363825Y401768D03*
X342900Y580126D03*
X362577Y752783D03*
X344109Y751809D03*
X343656Y933725D03*
X345578Y1047844D03*
X344099Y1106798D03*
X349855Y1104302D03*
X344130Y1401670D03*
X350690Y1403243D03*
X348710Y1570187D03*
X361011Y1568890D03*
X343402Y1572080D03*
X348245Y1575241D03*
X355364Y1570990D03*
X345537Y1916558D03*
X344402Y1911123D03*
X363361Y1918313D03*
X358318Y1920680D03*
X363411Y1923459D03*
X340336Y1922409D03*
X347676Y1922165D03*
X372204Y56126D03*
X365720Y52336D03*
X379257Y52158D03*
X379572Y58441D03*
X387524Y76847D03*
X374442Y406857D03*
X380619Y410112D03*
X380878Y403999D03*
X374542Y401282D03*
X368907Y404308D03*
X376654Y754748D03*
X382892Y767710D03*
X386790Y774338D03*
X380186Y761742D03*
X379335Y1189778D03*
X383276Y1184136D03*
X386816Y1179841D03*
X376472Y1194999D03*
X373674Y1199967D03*
X371523Y1204725D03*
X367829Y1566108D03*
X374775Y1919243D03*
X379403Y1917261D03*
X369748Y1921795D03*
X391278Y765894D03*
G54D33*
X307086Y308267D03*
G54D15*
X5491Y528544D03*
Y1603149D03*
X67499Y528544D03*
Y1603149D03*
G54D24*
X45056Y1817693D03*
G54D34*
X307086Y1883071D03*
G54D16*
X17480Y599901D03*
Y627264D03*
Y1471949D03*
Y1499311D03*
G54D25*
X65354Y101180D03*
X55511Y105117D03*
X51574Y114960D03*
X55511Y124803D03*
X65354Y128740D03*
Y451180D03*
X55511Y455117D03*
X51574Y464960D03*
X55511Y474803D03*
X65354Y478740D03*
Y801180D03*
X55511Y805117D03*
X51574Y814960D03*
X55511Y824803D03*
X65354Y828740D03*
Y1151180D03*
X55511Y1155117D03*
X51574Y1164960D03*
X55511Y1174803D03*
X65354Y1178740D03*
Y1501180D03*
X55511Y1505117D03*
X51574Y1514960D03*
X55511Y1524803D03*
X65354Y1528740D03*
Y1851180D03*
X55511Y1855117D03*
X51574Y1864960D03*
X55511Y1874803D03*
X65354Y1878740D03*
X75197Y105117D03*
Y124803D03*
X79134Y114960D03*
Y464960D03*
X75197Y455117D03*
Y474803D03*
Y805117D03*
Y824803D03*
X79134Y814960D03*
Y1164960D03*
X75197Y1155117D03*
Y1174803D03*
Y1505117D03*
Y1524803D03*
X79134Y1514960D03*
Y1864960D03*
X75197Y1855117D03*
Y1874803D03*
X307086Y113385D03*
X297243Y117322D03*
X293306Y127165D03*
X297243Y137008D03*
X307086Y140945D03*
Y463385D03*
X297243Y467322D03*
X293306Y477165D03*
X297243Y487008D03*
X307086Y490945D03*
Y813385D03*
X297243Y817322D03*
X293306Y827165D03*
X297243Y837008D03*
X307086Y840945D03*
Y1329724D03*
X297243Y1333661D03*
X293306Y1343504D03*
X297243Y1353347D03*
X307086Y1357284D03*
Y1679724D03*
X297243Y1683661D03*
X293306Y1693504D03*
X297243Y1703347D03*
X307086Y1707284D03*
X307087Y2029723D03*
X297244Y2033660D03*
X293307Y2043503D03*
X297244Y2053346D03*
X307087Y2057283D03*
X320866Y127165D03*
X316929Y117322D03*
Y137008D03*
Y467322D03*
Y487008D03*
X320866Y477165D03*
Y827165D03*
X316929Y817322D03*
Y837008D03*
Y1333661D03*
Y1353347D03*
X320866Y1343504D03*
Y1693504D03*
X316929Y1683661D03*
Y1703347D03*
X316930Y2033660D03*
Y2053346D03*
X320867Y2043503D03*
G54D26*
X65354Y114960D03*
Y464960D03*
Y814960D03*
Y1164960D03*
Y1514960D03*
Y1864960D03*
X307086Y127165D03*
Y477165D03*
Y827165D03*
Y1343504D03*
Y1693504D03*
X307087Y2043503D03*
G54D35*
X359842Y78780D03*
Y253780D03*
Y428779D03*
Y603779D03*
Y778780D03*
Y953780D03*
Y1128779D03*
Y1303780D03*
Y1478780D03*
Y1653780D03*
Y1828779D03*
Y2003780D03*
G54D17*
X9606Y599901D03*
Y627264D03*
Y1471949D03*
Y1499311D03*
G54D36*
G01X104331Y0D02*
X397638D01*
G03X405512Y7874I0J7874D01*
G01Y2078740D01*
G03X397638Y2086614I-7874J0D01*
G01X104331D01*
G03X98425Y2080709I0J-5906D01*
G01Y2076772D01*
G02X92520Y2070866I-5905J-1D01*
G01X5906D01*
G03X0Y2064961I-1J-5905D01*
G01Y21654D01*
G03X5906Y15748I5906J0D01*
G01X92520D01*
G02X98425Y9843I0J-5905D01*
G01Y5906D01*
G03X104331Y0I5906J0D01*
G54D27*
X55158Y882277D03*
X344826Y2035270D03*
X389572Y66182D03*
G54D18*
X15547Y707364D03*
X25389D03*
X7673Y703427D03*
X15547Y715238D03*
Y723112D03*
Y730986D03*
X25389Y715238D03*
Y723112D03*
Y730986D03*
X7673Y711301D03*
Y719175D03*
Y727049D03*
X15547Y738860D03*
Y746734D03*
Y754608D03*
X25389Y738860D03*
Y746734D03*
Y754608D03*
X7673Y734923D03*
Y742797D03*
Y750671D03*
Y758545D03*
X15547Y762483D03*
Y770357D03*
Y778231D03*
X25389Y762483D03*
Y770357D03*
Y778231D03*
X7673Y766419D03*
Y774293D03*
Y782167D03*
X15547Y786105D03*
Y793979D03*
Y801853D03*
X25389Y786105D03*
Y793979D03*
Y801853D03*
X7673Y790041D03*
Y797915D03*
Y805790D03*
X15547Y809727D03*
Y817601D03*
Y825475D03*
X25389Y809727D03*
Y817601D03*
Y825475D03*
X7673Y813664D03*
Y821538D03*
Y829412D03*
X15547Y833349D03*
Y841223D03*
Y849097D03*
X25389Y833349D03*
Y841223D03*
Y849097D03*
X7673Y837286D03*
Y845160D03*
Y853034D03*
X15547Y856971D03*
Y864845D03*
Y872719D03*
X25389Y856971D03*
Y864845D03*
Y872719D03*
X7673Y860908D03*
Y868782D03*
Y876656D03*
X15547Y880593D03*
Y888467D03*
Y896341D03*
X25389Y880593D03*
Y888467D03*
Y896341D03*
X7673Y884530D03*
Y892404D03*
Y900278D03*
X15547Y904215D03*
Y912089D03*
Y919963D03*
X25389Y904215D03*
Y912089D03*
Y919963D03*
X7673Y908152D03*
Y916026D03*
Y923900D03*
X15547Y927837D03*
Y935711D03*
Y943585D03*
Y951459D03*
X25389Y927837D03*
Y935711D03*
Y943585D03*
Y951459D03*
X7673Y931774D03*
Y939648D03*
Y947522D03*
X15547Y959333D03*
Y967207D03*
Y975081D03*
X25389Y959333D03*
Y967207D03*
Y975081D03*
X7673Y955396D03*
Y963270D03*
Y971144D03*
Y979018D03*
Y994766D03*
X15547Y990829D03*
Y998703D03*
X25389Y990829D03*
Y998703D03*
X7673Y1002640D03*
Y1010514D03*
Y1018388D03*
X15547Y1006577D03*
Y1014451D03*
Y1022325D03*
X25389Y1006577D03*
Y1014451D03*
Y1022325D03*
X7673Y1026262D03*
X15547Y1030199D03*
X15551Y1065629D03*
X25393D03*
X7677Y1061692D03*
Y1069566D03*
X15551Y1073503D03*
Y1081377D03*
Y1089251D03*
X25393Y1073503D03*
Y1081377D03*
Y1089251D03*
X7677Y1077440D03*
Y1085314D03*
Y1093188D03*
X15551Y1097125D03*
Y1104999D03*
Y1112873D03*
Y1120748D03*
X25393Y1097125D03*
Y1104999D03*
Y1112873D03*
Y1120748D03*
X7677Y1101062D03*
Y1108936D03*
Y1116810D03*
X15551Y1128622D03*
Y1136496D03*
Y1144370D03*
X25393Y1128622D03*
Y1136496D03*
Y1144370D03*
X7677Y1124684D03*
Y1132558D03*
Y1140432D03*
X15551Y1152244D03*
Y1160118D03*
Y1167992D03*
X25393Y1152244D03*
Y1160118D03*
Y1167992D03*
X7677Y1148306D03*
Y1156180D03*
Y1164055D03*
X15551Y1175866D03*
Y1183740D03*
Y1191614D03*
X25393Y1175866D03*
Y1183740D03*
Y1191614D03*
X7677Y1171929D03*
Y1179803D03*
Y1187677D03*
X15551Y1199488D03*
Y1207362D03*
Y1215236D03*
X25393Y1199488D03*
Y1207362D03*
Y1215236D03*
X7677Y1195551D03*
Y1203425D03*
Y1211299D03*
X15551Y1223110D03*
Y1230984D03*
Y1238858D03*
X25393Y1223110D03*
Y1230984D03*
Y1238858D03*
X7677Y1219173D03*
Y1227047D03*
Y1234921D03*
X15551Y1246732D03*
Y1254606D03*
Y1262480D03*
X25393Y1246732D03*
Y1254606D03*
Y1262480D03*
X7677Y1242795D03*
Y1250669D03*
Y1258543D03*
X15551Y1270354D03*
Y1278228D03*
Y1286102D03*
X25393Y1270354D03*
Y1278228D03*
Y1286102D03*
X7677Y1266417D03*
Y1274291D03*
Y1282165D03*
X15551Y1293976D03*
Y1301850D03*
Y1309724D03*
X25393Y1293976D03*
Y1301850D03*
Y1309724D03*
X7677Y1290039D03*
Y1297913D03*
Y1305787D03*
Y1313661D03*
X15551Y1317598D03*
Y1325472D03*
Y1333346D03*
X25393Y1317598D03*
Y1325472D03*
Y1333346D03*
X7677Y1321535D03*
Y1329409D03*
Y1337283D03*
Y1353031D03*
Y1360905D03*
X15551Y1349094D03*
Y1356968D03*
X25393Y1349094D03*
Y1356968D03*
X7677Y1368779D03*
Y1376653D03*
Y1384527D03*
X15551Y1364842D03*
Y1372716D03*
Y1380590D03*
X25393Y1364842D03*
Y1372716D03*
Y1380590D03*
X15551Y1388464D03*
X33263Y703427D03*
Y711301D03*
Y719175D03*
Y727049D03*
Y734923D03*
Y742797D03*
Y750671D03*
Y758545D03*
Y766419D03*
Y774293D03*
Y782167D03*
Y790041D03*
Y797915D03*
Y805790D03*
Y813664D03*
Y821538D03*
Y829412D03*
Y837286D03*
Y845160D03*
Y853034D03*
Y860908D03*
Y868782D03*
Y876656D03*
Y884530D03*
Y892404D03*
Y900278D03*
Y908152D03*
Y916026D03*
Y923900D03*
Y931774D03*
Y939648D03*
Y947522D03*
Y955396D03*
Y963270D03*
Y971144D03*
Y979018D03*
Y994766D03*
Y1002640D03*
Y1010514D03*
Y1018388D03*
Y1026262D03*
X33267Y1061692D03*
Y1069566D03*
Y1077440D03*
Y1085314D03*
Y1093188D03*
Y1101062D03*
Y1108936D03*
Y1116810D03*
Y1124684D03*
Y1132558D03*
Y1140432D03*
Y1148306D03*
Y1156180D03*
Y1164055D03*
Y1171929D03*
Y1179803D03*
Y1187677D03*
Y1195551D03*
Y1203425D03*
Y1211299D03*
Y1219173D03*
Y1227047D03*
Y1234921D03*
Y1242795D03*
Y1250669D03*
Y1258543D03*
Y1266417D03*
Y1274291D03*
Y1282165D03*
Y1290039D03*
Y1297913D03*
Y1305787D03*
Y1313661D03*
Y1321535D03*
Y1329409D03*
Y1337283D03*
Y1353031D03*
Y1360905D03*
Y1368779D03*
Y1376653D03*
Y1384527D03*
G54D37*
G01X-723776Y2987387D02*
Y-376795D01*
Y-489221D01*
X1782976D01*
Y-376795D01*
Y2987387D01*
X-723776D01*
G01X-4000Y-62500D02*
Y-137500D01*
X496000D01*
Y-62500D01*
X-4000D01*
G01X104331Y0D02*
X397638D01*
G03X405512Y7874I0J7874D01*
G01Y2078740D01*
G03X397638Y2086614I-7874J0D01*
G01X104331D01*
G03X98425Y2080709I0J-5906D01*
G01Y2076772D01*
G02X92520Y2070866I-5905J-1D01*
G01X5906D01*
G03X0Y2064961I-1J-5905D01*
G01Y21654D01*
G03X5906Y15748I5906J0D01*
G01X92520D01*
G02X98425Y9843I0J-5905D01*
G01Y5906D01*
G03X104331Y0I5906J0D01*
G01X8000Y-127500D02*
Y-132500D01*
G01X6543Y-127500D02*
X9457D01*
G01X14367Y-132500D02*
X11833D01*
Y-127500D01*
X14367D01*
G01X13353Y-129917D02*
X11833D01*
G01X16933Y-127500D02*
Y-132500D01*
X19467D01*
G01X23300Y-132667D02*
X23173Y-132583D01*
Y-132417D01*
X23300Y-132333D01*
X23427Y-132417D01*
Y-132583D01*
X23300Y-132667D01*
G01Y-130417D02*
X23173Y-130333D01*
Y-130167D01*
X23300Y-130083D01*
X23427Y-130167D01*
Y-130333D01*
X23300Y-130417D01*
G01X28083Y-134167D02*
X27450Y-133333D01*
X27133Y-132500D01*
Y-129167D01*
X27450Y-128333D01*
X28083Y-127500D01*
G01X33500D02*
X32993Y-127667D01*
X32613Y-128083D01*
X32360Y-128583D01*
X32170Y-129250D01*
X32107Y-130000D01*
X32170Y-130750D01*
X32360Y-131417D01*
X32613Y-131917D01*
X32993Y-132333D01*
X33500Y-132500D01*
X34007Y-132333D01*
X34387Y-131917D01*
X34640Y-131417D01*
X34830Y-130750D01*
X34893Y-130000D01*
X34830Y-129250D01*
X34640Y-128583D01*
X34387Y-128083D01*
X34007Y-127667D01*
X33500Y-127500D01*
G01X37207Y-131500D02*
X37587Y-132083D01*
X38093Y-132417D01*
X38663Y-132500D01*
X39170Y-132417D01*
X39677Y-132000D01*
X39993Y-131500D01*
X40057Y-131000D01*
X39930Y-130417D01*
X39487Y-130000D01*
X39043Y-129833D01*
X38473D01*
G01X39043D02*
X39423Y-129583D01*
X39740Y-129167D01*
X39867Y-128667D01*
X39740Y-128167D01*
X39423Y-127750D01*
X38853Y-127500D01*
X38283Y-127583D01*
X37713Y-127917D01*
G01X44017Y-134167D02*
X44650Y-133333D01*
X44967Y-132500D01*
Y-129167D01*
X44650Y-128333D01*
X44017Y-127500D01*
G01X47407Y-131500D02*
X47787Y-132083D01*
X48293Y-132417D01*
X48863Y-132500D01*
X49370Y-132417D01*
X49877Y-132000D01*
X50193Y-131500D01*
X50257Y-131000D01*
X50130Y-130417D01*
X49687Y-130000D01*
X49243Y-129833D01*
X48673D01*
G01X49243D02*
X49623Y-129583D01*
X49940Y-129167D01*
X50067Y-128667D01*
X49940Y-128167D01*
X49623Y-127750D01*
X49053Y-127500D01*
X48483Y-127583D01*
X47913Y-127917D01*
G01X52697Y-128333D02*
X53077Y-127833D01*
X53520Y-127583D01*
X54027Y-127500D01*
X54660Y-127667D01*
X55103Y-128083D01*
X55230Y-128583D01*
X55167Y-129083D01*
X54913Y-129500D01*
X53647Y-130333D01*
X53077Y-130917D01*
X52697Y-131750D01*
X52570Y-132500D01*
X55230D01*
G01X58873D02*
X59000Y-131417D01*
X59190Y-130500D01*
X59443Y-129667D01*
X59760Y-128750D01*
X60267Y-127500D01*
X57733D01*
G01X63277Y-130833D02*
X64923D01*
G01X67997Y-128333D02*
X68377Y-127833D01*
X68820Y-127583D01*
X69327Y-127500D01*
X69960Y-127667D01*
X70403Y-128083D01*
X70530Y-128583D01*
X70467Y-129083D01*
X70213Y-129500D01*
X68947Y-130333D01*
X68377Y-130917D01*
X67997Y-131750D01*
X67870Y-132500D01*
X70530D01*
G01X72907Y-131500D02*
X73287Y-132083D01*
X73793Y-132417D01*
X74363Y-132500D01*
X74870Y-132417D01*
X75377Y-132000D01*
X75693Y-131500D01*
X75757Y-131000D01*
X75630Y-130417D01*
X75187Y-130000D01*
X74743Y-129833D01*
X74173D01*
G01X74743D02*
X75123Y-129583D01*
X75440Y-129167D01*
X75567Y-128667D01*
X75440Y-128167D01*
X75123Y-127750D01*
X74553Y-127500D01*
X73983Y-127583D01*
X73413Y-127917D01*
G01X80160Y-132500D02*
Y-127500D01*
X77817Y-131083D01*
X80983D01*
G01X83107Y-131750D02*
X83487Y-132167D01*
X83930Y-132417D01*
X84500Y-132500D01*
X85070Y-132333D01*
X85513Y-132000D01*
X85830Y-131417D01*
X85893Y-130750D01*
X85767Y-130083D01*
X85450Y-129667D01*
X85007Y-129333D01*
X84563Y-129250D01*
X84120Y-129333D01*
X83550Y-129667D01*
X83740Y-127500D01*
X85450D01*
G01X93497Y-132500D02*
Y-127500D01*
X95903D01*
G01X95017Y-129917D02*
X93497D01*
G01X98217Y-132500D02*
X99800Y-127500D01*
X101383Y-132500D01*
G01X100813Y-130750D02*
X98787D01*
G01X103570Y-132500D02*
X106230Y-127500D01*
G01X103570D02*
X106230Y-132500D01*
G01X110000Y-132667D02*
X109873Y-132583D01*
Y-132417D01*
X110000Y-132333D01*
X110127Y-132417D01*
Y-132583D01*
X110000Y-132667D01*
G01Y-130417D02*
X109873Y-130333D01*
Y-130167D01*
X110000Y-130083D01*
X110127Y-130167D01*
Y-130333D01*
X110000Y-130417D01*
G01X114783Y-134167D02*
X114150Y-133333D01*
X113833Y-132500D01*
Y-129167D01*
X114150Y-128333D01*
X114783Y-127500D01*
G01X120200D02*
X119693Y-127667D01*
X119313Y-128083D01*
X119060Y-128583D01*
X118870Y-129250D01*
X118807Y-130000D01*
X118870Y-130750D01*
X119060Y-131417D01*
X119313Y-131917D01*
X119693Y-132333D01*
X120200Y-132500D01*
X120707Y-132333D01*
X121087Y-131917D01*
X121340Y-131417D01*
X121530Y-130750D01*
X121593Y-130000D01*
X121530Y-129250D01*
X121340Y-128583D01*
X121087Y-128083D01*
X120707Y-127667D01*
X120200Y-127500D01*
G01X123907Y-131500D02*
X124287Y-132083D01*
X124793Y-132417D01*
X125363Y-132500D01*
X125870Y-132417D01*
X126377Y-132000D01*
X126693Y-131500D01*
X126757Y-131000D01*
X126630Y-130417D01*
X126187Y-130000D01*
X125743Y-129833D01*
X125173D01*
G01X125743D02*
X126123Y-129583D01*
X126440Y-129167D01*
X126567Y-128667D01*
X126440Y-128167D01*
X126123Y-127750D01*
X125553Y-127500D01*
X124983Y-127583D01*
X124413Y-127917D01*
G01X130717Y-134167D02*
X131350Y-133333D01*
X131667Y-132500D01*
Y-129167D01*
X131350Y-128333D01*
X130717Y-127500D01*
G01X134107Y-131500D02*
X134487Y-132083D01*
X134993Y-132417D01*
X135563Y-132500D01*
X136070Y-132417D01*
X136577Y-132000D01*
X136893Y-131500D01*
X136957Y-131000D01*
X136830Y-130417D01*
X136387Y-130000D01*
X135943Y-129833D01*
X135373D01*
G01X135943D02*
X136323Y-129583D01*
X136640Y-129167D01*
X136767Y-128667D01*
X136640Y-128167D01*
X136323Y-127750D01*
X135753Y-127500D01*
X135183Y-127583D01*
X134613Y-127917D01*
G01X139523Y-131917D02*
X139967Y-132333D01*
X140473Y-132500D01*
X140980Y-132333D01*
X141423Y-131833D01*
X141740Y-131083D01*
X141867Y-130333D01*
Y-129417D01*
X141740Y-128667D01*
X141423Y-128000D01*
X141043Y-127667D01*
X140600Y-127500D01*
X140093Y-127667D01*
X139713Y-128000D01*
X139460Y-128500D01*
X139333Y-129167D01*
X139460Y-129750D01*
X139777Y-130333D01*
X140157Y-130667D01*
X140600Y-130750D01*
X141107Y-130583D01*
X141487Y-130167D01*
X141867Y-129417D01*
G01X145573Y-132500D02*
X145700Y-131417D01*
X145890Y-130500D01*
X146143Y-129667D01*
X146460Y-128750D01*
X146967Y-127500D01*
X144433D01*
G01X149977Y-130833D02*
X151623D01*
G01X154507Y-131500D02*
X154887Y-132083D01*
X155393Y-132417D01*
X155963Y-132500D01*
X156470Y-132417D01*
X156977Y-132000D01*
X157293Y-131500D01*
X157357Y-131000D01*
X157230Y-130417D01*
X156787Y-130000D01*
X156343Y-129833D01*
X155773D01*
G01X156343D02*
X156723Y-129583D01*
X157040Y-129167D01*
X157167Y-128667D01*
X157040Y-128167D01*
X156723Y-127750D01*
X156153Y-127500D01*
X155583Y-127583D01*
X155013Y-127917D01*
G01X159797Y-130417D02*
X160240Y-129833D01*
X160620Y-129500D01*
X161127Y-129333D01*
X161570Y-129500D01*
X161887Y-129833D01*
X162140Y-130333D01*
X162203Y-130917D01*
X162140Y-131417D01*
X161887Y-131917D01*
X161507Y-132333D01*
X161063Y-132500D01*
X160557Y-132333D01*
X160113Y-131833D01*
X159860Y-131083D01*
X159797Y-130250D01*
X159923Y-129167D01*
X160113Y-128583D01*
X160430Y-128000D01*
X160873Y-127583D01*
X161317Y-127500D01*
X161760Y-127667D01*
X162077Y-128083D01*
G01X166100Y-132500D02*
Y-127500D01*
X165340Y-128500D01*
G01Y-132500D02*
X166860D01*
G01X171960D02*
Y-127500D01*
X169617Y-131083D01*
X172783D01*
G01X191000Y-62500D02*
Y-137500D01*
G01Y-112500D02*
X294000D01*
Y-87500D01*
G01X191000D02*
X294000D01*
G01X301507Y-122500D02*
Y-117500D01*
X302773D01*
X303280Y-117750D01*
X303660Y-118083D01*
X303977Y-118583D01*
X304230Y-119167D01*
X304293Y-120000D01*
X304230Y-120833D01*
X303977Y-121417D01*
X303660Y-121917D01*
X303280Y-122250D01*
X302773Y-122500D01*
X301507D01*
G01X306417D02*
X308000Y-117500D01*
X309583Y-122500D01*
G01X309013Y-120750D02*
X306987D01*
G01X313100Y-117500D02*
Y-122500D01*
G01X311643Y-117500D02*
X314557D01*
G01X319467Y-122500D02*
X316933D01*
Y-117500D01*
X319467D01*
G01X318453Y-119917D02*
X316933D01*
G01X323300Y-122667D02*
X323173Y-122583D01*
Y-122417D01*
X323300Y-122333D01*
X323427Y-122417D01*
Y-122583D01*
X323300Y-122667D01*
G01Y-120417D02*
X323173Y-120333D01*
Y-120167D01*
X323300Y-120083D01*
X323427Y-120167D01*
Y-120333D01*
X323300Y-120417D01*
G01X296000Y-62500D02*
Y-137500D01*
G01X294000Y-62500D02*
Y-137500D01*
G01X301633Y-97500D02*
Y-92500D01*
X303153D01*
X303660Y-92750D01*
X304040Y-93333D01*
X304167Y-94000D01*
X304040Y-94667D01*
X303723Y-95167D01*
X303153Y-95417D01*
X301633D01*
G01X306860Y-97667D02*
X309140Y-92500D01*
G01X311643Y-97500D02*
Y-92500D01*
X314557Y-97500D01*
Y-92500D01*
G01X318200Y-97667D02*
X318073Y-97583D01*
Y-97417D01*
X318200Y-97333D01*
X318327Y-97417D01*
Y-97583D01*
X318200Y-97667D01*
G01Y-95417D02*
X318073Y-95333D01*
Y-95167D01*
X318200Y-95083D01*
X318327Y-95167D01*
Y-95333D01*
X318200Y-95417D01*
G01X296000Y-112500D02*
X496000D01*
G01X301633Y-72500D02*
Y-67500D01*
X303153D01*
X303660Y-67750D01*
X304040Y-68333D01*
X304167Y-69000D01*
X304040Y-69667D01*
X303723Y-70167D01*
X303153Y-70417D01*
X301633D01*
G01X306733Y-72500D02*
Y-67500D01*
X308317D01*
X308823Y-67750D01*
X309140Y-68083D01*
X309267Y-68750D01*
X309140Y-69417D01*
X308760Y-69833D01*
X308317Y-70083D01*
X306733D01*
G01X308317D02*
X309267Y-72500D01*
G01X313100D02*
X312593Y-72417D01*
X312150Y-72083D01*
X311770Y-71583D01*
X311517Y-71000D01*
X311390Y-70333D01*
Y-69667D01*
X311517Y-69000D01*
X311770Y-68417D01*
X312150Y-67917D01*
X312593Y-67583D01*
X313100Y-67500D01*
X313607Y-67583D01*
X314050Y-67917D01*
X314430Y-68417D01*
X314683Y-69000D01*
X314810Y-69667D01*
Y-70333D01*
X314683Y-71000D01*
X314430Y-71583D01*
X314050Y-72083D01*
X313607Y-72417D01*
X313100Y-72500D01*
G01X316933Y-71500D02*
X317250Y-72000D01*
X317630Y-72333D01*
X318073Y-72500D01*
X318580Y-72333D01*
X318960Y-72000D01*
X319340Y-71500D01*
X319467Y-70833D01*
Y-67500D01*
G01X324567Y-72500D02*
X322033D01*
Y-67500D01*
X324567D01*
G01X323553Y-69917D02*
X322033D01*
G01X329793Y-67917D02*
X329413Y-67667D01*
X328970Y-67500D01*
X328463D01*
X327893Y-67750D01*
X327450Y-68167D01*
X327133Y-68667D01*
X326880Y-69500D01*
X326817Y-70250D01*
X326943Y-71000D01*
X327133Y-71500D01*
X327513Y-72000D01*
X327957Y-72333D01*
X328400Y-72500D01*
X328843D01*
X329287Y-72333D01*
X329667Y-72083D01*
X329983Y-71750D01*
G01X333500Y-67500D02*
Y-72500D01*
G01X332043Y-67500D02*
X334957D01*
G01X338600Y-72667D02*
X338473Y-72583D01*
Y-72417D01*
X338600Y-72333D01*
X338727Y-72417D01*
Y-72583D01*
X338600Y-72667D01*
G01Y-70417D02*
X338473Y-70333D01*
Y-70167D01*
X338600Y-70083D01*
X338727Y-70167D01*
Y-70333D01*
X338600Y-70417D01*
G01X296000Y-87500D02*
X496000D01*
G01X411000Y-112500D02*
Y-137500D01*
G01X416633Y-122500D02*
Y-117500D01*
X418217D01*
X418723Y-117750D01*
X419040Y-118083D01*
X419167Y-118750D01*
X419040Y-119417D01*
X418660Y-119833D01*
X418217Y-120083D01*
X416633D01*
G01X418217D02*
X419167Y-122500D01*
G01X424267D02*
X421733D01*
Y-117500D01*
X424267D01*
G01X423253Y-119917D02*
X421733D01*
G01X426517Y-117500D02*
X428100Y-122500D01*
X429683Y-117500D01*
G01X433200Y-122667D02*
X433073Y-122583D01*
Y-122417D01*
X433200Y-122333D01*
X433327Y-122417D01*
Y-122583D01*
X433200Y-122667D01*
G01Y-120417D02*
X433073Y-120333D01*
Y-120167D01*
X433200Y-120083D01*
X433327Y-120167D01*
Y-120333D01*
X433200Y-120417D01*
G01X460000Y-112500D02*
Y-137500D01*
G01X-723776Y2987387D02*
Y-376795D01*
Y-489221D01*
X1782976D01*
Y-376795D01*
Y2987387D01*
X-723776D01*
G01X6705Y-124160D02*
X7332Y-124685D01*
X8037Y-125000D01*
X8663D01*
X9290Y-124685D01*
X9760Y-124160D01*
X9995Y-123425D01*
X9838Y-122690D01*
X9447Y-122060D01*
X8742Y-121640D01*
X7802Y-121430D01*
X7253Y-121010D01*
X7018Y-120275D01*
X7175Y-119540D01*
X7567Y-119015D01*
X8115Y-118700D01*
X8663D01*
X9212Y-118910D01*
X9682Y-119435D01*
G01X13005Y-125000D02*
Y-118700D01*
G01X16295D02*
Y-125000D01*
G01Y-121850D02*
X13005D01*
G01X20010Y-118700D02*
X21890D01*
G01X20950D02*
Y-125000D01*
G01X20010D02*
X21890D01*
G01X28817D02*
X25683D01*
Y-118700D01*
X28817D01*
G01X27563Y-121745D02*
X25683D01*
G01X31748Y-125000D02*
Y-118700D01*
X35352Y-125000D01*
Y-118700D01*
G01X39693Y-126155D02*
X40007Y-124790D01*
G01X46150Y-118700D02*
Y-125000D01*
G01X44348Y-118700D02*
X47952D01*
G01X50492Y-125000D02*
X52450Y-118700D01*
X54408Y-125000D01*
G01X53703Y-122795D02*
X51197D01*
G01X57810Y-118700D02*
X59690D01*
G01X58750D02*
Y-125000D01*
G01X57810D02*
X59690D01*
G01X62700Y-118700D02*
X63797Y-125000D01*
X65050Y-118700D01*
X66303Y-125000D01*
X67400Y-118700D01*
G01X69392Y-125000D02*
X71350Y-118700D01*
X73308Y-125000D01*
G01X72603Y-122795D02*
X70097D01*
G01X75848Y-125000D02*
Y-118700D01*
X79452Y-125000D01*
Y-118700D01*
G01X88683Y-125000D02*
Y-118700D01*
X90642D01*
X91268Y-119015D01*
X91660Y-119435D01*
X91817Y-120275D01*
X91660Y-121115D01*
X91190Y-121640D01*
X90642Y-121955D01*
X88683D01*
G01X90642D02*
X91817Y-125000D01*
G01X96550Y-125210D02*
X96393Y-125105D01*
Y-124895D01*
X96550Y-124790D01*
X96707Y-124895D01*
Y-125105D01*
X96550Y-125210D01*
G01X102850Y-125000D02*
X102223Y-124895D01*
X101675Y-124475D01*
X101205Y-123845D01*
X100892Y-123110D01*
X100735Y-122270D01*
Y-121430D01*
X100892Y-120590D01*
X101205Y-119855D01*
X101675Y-119225D01*
X102223Y-118805D01*
X102850Y-118700D01*
X103477Y-118805D01*
X104025Y-119225D01*
X104495Y-119855D01*
X104808Y-120590D01*
X104965Y-121430D01*
Y-122270D01*
X104808Y-123110D01*
X104495Y-123845D01*
X104025Y-124475D01*
X103477Y-124895D01*
X102850Y-125000D01*
G01X109150Y-125210D02*
X108993Y-125105D01*
Y-124895D01*
X109150Y-124790D01*
X109307Y-124895D01*
Y-125105D01*
X109150Y-125210D01*
G01X117173Y-119225D02*
X116703Y-118910D01*
X116155Y-118700D01*
X115528D01*
X114823Y-119015D01*
X114275Y-119540D01*
X113883Y-120170D01*
X113570Y-121220D01*
X113492Y-122165D01*
X113648Y-123110D01*
X113883Y-123740D01*
X114353Y-124370D01*
X114902Y-124790D01*
X115450Y-125000D01*
X115998D01*
X116547Y-124790D01*
X117017Y-124475D01*
X117408Y-124055D01*
G01X121750Y-125210D02*
X121593Y-125105D01*
Y-124895D01*
X121750Y-124790D01*
X121907Y-124895D01*
Y-125105D01*
X121750Y-125210D01*
G01X6627Y-115000D02*
Y-108700D01*
G01X9603D02*
X6627Y-112585D01*
G01X10073Y-115000D02*
X7958Y-110800D01*
G01X12927Y-108700D02*
Y-113215D01*
X13240Y-114160D01*
X13867Y-114790D01*
X14650Y-115000D01*
X15433Y-114790D01*
X16060Y-114160D01*
X16373Y-113215D01*
Y-108700D01*
G01X22517Y-115000D02*
X19383D01*
Y-108700D01*
X22517D01*
G01X21263Y-111745D02*
X19383D01*
G01X26310Y-108700D02*
X28190D01*
G01X27250D02*
Y-115000D01*
G01X26310D02*
X28190D01*
G01X38205Y-114160D02*
X38832Y-114685D01*
X39537Y-115000D01*
X40163D01*
X40790Y-114685D01*
X41260Y-114160D01*
X41495Y-113425D01*
X41338Y-112690D01*
X40947Y-112060D01*
X40242Y-111640D01*
X39302Y-111430D01*
X38753Y-111010D01*
X38518Y-110275D01*
X38675Y-109540D01*
X39067Y-109015D01*
X39615Y-108700D01*
X40163D01*
X40712Y-108910D01*
X41182Y-109435D01*
G01X44505Y-115000D02*
Y-108700D01*
G01X47795D02*
Y-115000D01*
G01Y-111850D02*
X44505D01*
G01X50492Y-115000D02*
X52450Y-108700D01*
X54408Y-115000D01*
G01X53703Y-112795D02*
X51197D01*
G01X56948Y-115000D02*
Y-108700D01*
X60552Y-115000D01*
Y-108700D01*
G01X69705Y-115000D02*
Y-108700D01*
G01X72995D02*
Y-115000D01*
G01Y-111850D02*
X69705D01*
G01X76005Y-114160D02*
X76632Y-114685D01*
X77337Y-115000D01*
X77963D01*
X78590Y-114685D01*
X79060Y-114160D01*
X79295Y-113425D01*
X79138Y-112690D01*
X78747Y-112060D01*
X78042Y-111640D01*
X77102Y-111430D01*
X76553Y-111010D01*
X76318Y-110275D01*
X76475Y-109540D01*
X76867Y-109015D01*
X77415Y-108700D01*
X77963D01*
X78512Y-108910D01*
X78982Y-109435D01*
G01X83010Y-108700D02*
X84890D01*
G01X83950D02*
Y-115000D01*
G01X83010D02*
X84890D01*
G01X88292D02*
X90250Y-108700D01*
X92208Y-115000D01*
G01X91503Y-112795D02*
X88997D01*
G01X94748Y-115000D02*
Y-108700D01*
X98352Y-115000D01*
Y-108700D01*
G01X103320Y-111850D02*
X104887D01*
Y-113740D01*
X104417Y-114370D01*
X103868Y-114790D01*
X103085Y-115000D01*
X102302Y-114790D01*
X101753Y-114370D01*
X101283Y-113740D01*
X100970Y-113005D01*
X100813Y-112165D01*
Y-111430D01*
X100970Y-110800D01*
X101283Y-110065D01*
X101753Y-109435D01*
X102223Y-109015D01*
X102850Y-108700D01*
X103398D01*
X104025Y-108910D01*
X104495Y-109330D01*
G01X108993Y-116155D02*
X109307Y-114790D01*
G01X115450Y-108700D02*
Y-115000D01*
G01X113648Y-108700D02*
X117252D01*
G01X119792Y-115000D02*
X121750Y-108700D01*
X123708Y-115000D01*
G01X123003Y-112795D02*
X120497D01*
G01X128050Y-115000D02*
X127423Y-114895D01*
X126875Y-114475D01*
X126405Y-113845D01*
X126092Y-113110D01*
X125935Y-112270D01*
Y-111430D01*
X126092Y-110590D01*
X126405Y-109855D01*
X126875Y-109225D01*
X127423Y-108805D01*
X128050Y-108700D01*
X128677Y-108805D01*
X129225Y-109225D01*
X129695Y-109855D01*
X130008Y-110590D01*
X130165Y-111430D01*
Y-112270D01*
X130008Y-113110D01*
X129695Y-113845D01*
X129225Y-114475D01*
X128677Y-114895D01*
X128050Y-115000D01*
G01X140650D02*
Y-112165D01*
X139083Y-108700D01*
G01X142217D02*
X140650Y-112165D01*
G01X145227Y-108700D02*
Y-113215D01*
X145540Y-114160D01*
X146167Y-114790D01*
X146950Y-115000D01*
X147733Y-114790D01*
X148360Y-114160D01*
X148673Y-113215D01*
Y-108700D01*
G01X151292Y-115000D02*
X153250Y-108700D01*
X155208Y-115000D01*
G01X154503Y-112795D02*
X151997D01*
G01X157748Y-115000D02*
Y-108700D01*
X161352Y-115000D01*
Y-108700D01*
G01X30650Y-92300D02*
X28130Y-91883D01*
X25925Y-90217D01*
X24035Y-87717D01*
X22775Y-84800D01*
X22145Y-81467D01*
Y-78133D01*
X22775Y-74800D01*
X24035Y-71883D01*
X25925Y-69384D01*
X28130Y-67717D01*
X30650Y-67300D01*
X33170Y-67717D01*
X35375Y-69384D01*
X37265Y-71883D01*
X38525Y-74800D01*
X39155Y-78133D01*
Y-81467D01*
X38525Y-84800D01*
X37265Y-87717D01*
X35375Y-90217D01*
X33170Y-91883D01*
X30650Y-92300D01*
G01X33170Y-85633D02*
X36950Y-92300D01*
G01X50495Y-75634D02*
Y-87300D01*
X51755Y-90217D01*
X53645Y-91883D01*
X55850Y-92300D01*
X58055Y-91883D01*
X59945Y-90217D01*
X61205Y-87300D01*
G01Y-92300D02*
Y-75634D01*
G01X86720Y-92300D02*
Y-75634D01*
G01Y-78550D02*
X85460Y-76884D01*
X83570Y-76050D01*
X81365Y-75634D01*
X79160Y-76467D01*
X77270Y-78133D01*
X76010Y-80634D01*
X75380Y-83967D01*
X76010Y-87300D01*
X77270Y-89801D01*
X79160Y-91467D01*
X81365Y-92300D01*
X83570Y-91883D01*
X85460Y-90634D01*
X86720Y-88967D01*
G01X100895Y-92300D02*
Y-75634D01*
G01Y-79800D02*
X102155Y-77717D01*
X104045Y-76050D01*
X106565Y-75634D01*
X108770Y-76050D01*
X110660Y-77717D01*
X111605Y-80634D01*
Y-92300D01*
G01X131450Y-67300D02*
Y-92300D01*
G01X127040Y-75634D02*
X135860D01*
G01X162320Y-92300D02*
Y-75634D01*
G01Y-78550D02*
X161060Y-76884D01*
X159170Y-76050D01*
X156965Y-75634D01*
X154760Y-76467D01*
X152870Y-78133D01*
X151610Y-80634D01*
X150980Y-83967D01*
X151610Y-87300D01*
X152870Y-89801D01*
X154760Y-91467D01*
X156965Y-92300D01*
X159170Y-91883D01*
X161060Y-90634D01*
X162320Y-88967D01*
G01X6548Y-105000D02*
Y-98700D01*
X10152Y-105000D01*
Y-98700D01*
G01X14650Y-105000D02*
X14023Y-104895D01*
X13475Y-104475D01*
X13005Y-103845D01*
X12692Y-103110D01*
X12535Y-102270D01*
Y-101430D01*
X12692Y-100590D01*
X13005Y-99855D01*
X13475Y-99225D01*
X14023Y-98805D01*
X14650Y-98700D01*
X15277Y-98805D01*
X15825Y-99225D01*
X16295Y-99855D01*
X16608Y-100590D01*
X16765Y-101430D01*
Y-102270D01*
X16608Y-103110D01*
X16295Y-103845D01*
X15825Y-104475D01*
X15277Y-104895D01*
X14650Y-105000D01*
G01X20950Y-105210D02*
X20793Y-105105D01*
Y-104895D01*
X20950Y-104790D01*
X21107Y-104895D01*
Y-105105D01*
X20950Y-105210D01*
G01X27250Y-105000D02*
Y-98700D01*
X26310Y-99960D01*
G01Y-105000D02*
X28190D01*
G01X33550D02*
X34098Y-104895D01*
X34725Y-104580D01*
X35117Y-104055D01*
X35273Y-103320D01*
X35117Y-102585D01*
X34647Y-101955D01*
X33942Y-101640D01*
X33158D01*
X32688Y-101430D01*
X32297Y-100905D01*
X32140Y-100170D01*
X32375Y-99435D01*
X32923Y-98910D01*
X33550Y-98700D01*
X34177Y-98910D01*
X34725Y-99435D01*
X34960Y-100170D01*
X34803Y-100905D01*
X34412Y-101430D01*
X33942Y-101640D01*
X33158D01*
X32453Y-101955D01*
X31983Y-102585D01*
X31827Y-103320D01*
X31983Y-104055D01*
X32375Y-104580D01*
X33002Y-104895D01*
X33550Y-105000D01*
G01X39850D02*
X40398Y-104895D01*
X41025Y-104580D01*
X41417Y-104055D01*
X41573Y-103320D01*
X41417Y-102585D01*
X40947Y-101955D01*
X40242Y-101640D01*
X39458D01*
X38988Y-101430D01*
X38597Y-100905D01*
X38440Y-100170D01*
X38675Y-99435D01*
X39223Y-98910D01*
X39850Y-98700D01*
X40477Y-98910D01*
X41025Y-99435D01*
X41260Y-100170D01*
X41103Y-100905D01*
X40712Y-101430D01*
X40242Y-101640D01*
X39458D01*
X38753Y-101955D01*
X38283Y-102585D01*
X38127Y-103320D01*
X38283Y-104055D01*
X38675Y-104580D01*
X39302Y-104895D01*
X39850Y-105000D01*
G01X45993Y-106155D02*
X46307Y-104790D01*
G01X50100Y-98700D02*
X51197Y-105000D01*
X52450Y-98700D01*
X53703Y-105000D01*
X54800Y-98700D01*
G01X60317Y-105000D02*
X57183D01*
Y-98700D01*
X60317D01*
G01X59063Y-101745D02*
X57183D01*
G01X63248Y-105000D02*
Y-98700D01*
X66852Y-105000D01*
Y-98700D01*
G01X76005Y-105000D02*
Y-98700D01*
G01X79295D02*
Y-105000D01*
G01Y-101850D02*
X76005D01*
G01X81600Y-98700D02*
X82697Y-105000D01*
X83950Y-98700D01*
X85203Y-105000D01*
X86300Y-98700D01*
G01X88292Y-105000D02*
X90250Y-98700D01*
X92208Y-105000D01*
G01X91503Y-102795D02*
X88997D01*
G01X101362Y-99750D02*
X101832Y-99120D01*
X102380Y-98805D01*
X103007Y-98700D01*
X103790Y-98910D01*
X104338Y-99435D01*
X104495Y-100065D01*
X104417Y-100695D01*
X104103Y-101220D01*
X102537Y-102270D01*
X101832Y-103005D01*
X101362Y-104055D01*
X101205Y-105000D01*
X104495D01*
G01X107348D02*
Y-98700D01*
X110952Y-105000D01*
Y-98700D01*
G01X113727Y-105000D02*
Y-98700D01*
X115293D01*
X115920Y-99015D01*
X116390Y-99435D01*
X116782Y-100065D01*
X117095Y-100800D01*
X117173Y-101850D01*
X117095Y-102900D01*
X116782Y-103635D01*
X116390Y-104265D01*
X115920Y-104685D01*
X115293Y-105000D01*
X113727D01*
G01X126483D02*
Y-98700D01*
X128442D01*
X129068Y-99015D01*
X129460Y-99435D01*
X129617Y-100275D01*
X129460Y-101115D01*
X128990Y-101640D01*
X128442Y-101955D01*
X126483D01*
G01X128442D02*
X129617Y-105000D01*
G01X132627D02*
Y-98700D01*
X134193D01*
X134820Y-99015D01*
X135290Y-99435D01*
X135682Y-100065D01*
X135995Y-100800D01*
X136073Y-101850D01*
X135995Y-102900D01*
X135682Y-103635D01*
X135290Y-104265D01*
X134820Y-104685D01*
X134193Y-105000D01*
X132627D01*
G01X140650Y-105210D02*
X140493Y-105105D01*
Y-104895D01*
X140650Y-104790D01*
X140807Y-104895D01*
Y-105105D01*
X140650Y-105210D01*
G01X215400Y-105000D02*
Y-97000D01*
X218000Y-103667D01*
X220600Y-97000D01*
Y-105000D01*
G01X223500D02*
X226000Y-97000D01*
X228500Y-105000D01*
G01X227600Y-102200D02*
X224400D01*
G01X231900Y-103934D02*
X232700Y-104600D01*
X233600Y-105000D01*
X234400D01*
X235200Y-104600D01*
X235800Y-103934D01*
X236100Y-103000D01*
X235900Y-102067D01*
X235400Y-101267D01*
X234500Y-100733D01*
X233300Y-100467D01*
X232600Y-99933D01*
X232300Y-99000D01*
X232500Y-98067D01*
X233000Y-97400D01*
X233700Y-97000D01*
X234400D01*
X235100Y-97267D01*
X235700Y-97933D01*
G01X239800Y-105000D02*
Y-97000D01*
G01X243600D02*
X239800Y-101934D01*
G01X244200Y-105000D02*
X241500Y-99667D01*
G01X248700Y-102333D02*
X251300D01*
G01X258800Y-100733D02*
X259200Y-100333D01*
X259500Y-99667D01*
X259700Y-98733D01*
X259500Y-97933D01*
X259100Y-97400D01*
X258400Y-97000D01*
X255700D01*
Y-105000D01*
X259000D01*
X259700Y-104467D01*
X260100Y-103667D01*
X260300Y-102733D01*
X260100Y-101800D01*
X259500Y-101000D01*
X258800Y-100733D01*
X255700D01*
G01X266000Y-105000D02*
X265200Y-104867D01*
X264500Y-104333D01*
X263900Y-103533D01*
X263500Y-102600D01*
X263300Y-101533D01*
Y-100467D01*
X263500Y-99400D01*
X263900Y-98467D01*
X264500Y-97667D01*
X265200Y-97133D01*
X266000Y-97000D01*
X266800Y-97133D01*
X267500Y-97667D01*
X268100Y-98467D01*
X268500Y-99400D01*
X268700Y-100467D01*
Y-101533D01*
X268500Y-102600D01*
X268100Y-103533D01*
X267500Y-104333D01*
X266800Y-104867D01*
X266000Y-105000D01*
G01X274000Y-97000D02*
Y-105000D01*
G01X271700Y-97000D02*
X276300D01*
G01X202000Y-72000D02*
Y-80000D01*
X206000D01*
G01X213800D02*
Y-74667D01*
G01Y-75600D02*
X213400Y-75067D01*
X212800Y-74800D01*
X212100Y-74667D01*
X211400Y-74933D01*
X210800Y-75467D01*
X210400Y-76267D01*
X210200Y-77333D01*
X210400Y-78400D01*
X210800Y-79200D01*
X211400Y-79733D01*
X212100Y-80000D01*
X212800Y-79867D01*
X213400Y-79467D01*
X213800Y-78934D01*
G01X217900Y-82400D02*
X218500Y-82667D01*
X219300Y-82400D01*
X219800Y-81867D01*
X220200Y-81200D01*
X220800Y-79067D01*
X222100Y-74667D01*
G01X218900D02*
X220800Y-79067D01*
G01X226500Y-76400D02*
X229700D01*
X229400Y-75467D01*
X228900Y-74933D01*
X228200Y-74667D01*
X227500Y-74800D01*
X226900Y-75200D01*
X226500Y-76133D01*
X226300Y-76934D01*
Y-77733D01*
X226500Y-78533D01*
X227000Y-79333D01*
X227600Y-79867D01*
X228300Y-80000D01*
X229000Y-79733D01*
X229700Y-78934D01*
G01X234600Y-80000D02*
Y-74667D01*
G01Y-75733D02*
X235100Y-75200D01*
X235600Y-74800D01*
X236300Y-74667D01*
X236800Y-74800D01*
X237400Y-75200D01*
G01X223400Y-128934D02*
X224200Y-129600D01*
X225100Y-130000D01*
X225900D01*
X226700Y-129600D01*
X227300Y-128934D01*
X227600Y-128000D01*
X227400Y-127067D01*
X226900Y-126267D01*
X226000Y-125733D01*
X224800Y-125467D01*
X224100Y-124933D01*
X223800Y-124000D01*
X224000Y-123067D01*
X224500Y-122400D01*
X225200Y-122000D01*
X225900D01*
X226600Y-122267D01*
X227200Y-122933D01*
G01X235300Y-130000D02*
Y-124667D01*
G01Y-125600D02*
X234900Y-125067D01*
X234300Y-124800D01*
X233600Y-124667D01*
X232900Y-124933D01*
X232300Y-125467D01*
X231900Y-126267D01*
X231700Y-127333D01*
X231900Y-128400D01*
X232300Y-129200D01*
X232900Y-129733D01*
X233600Y-130000D01*
X234300Y-129867D01*
X234900Y-129467D01*
X235300Y-128934D01*
G01X239800Y-130000D02*
Y-124667D01*
G01Y-126000D02*
X240200Y-125333D01*
X240800Y-124800D01*
X241600Y-124667D01*
X242300Y-124800D01*
X242900Y-125333D01*
X243200Y-126267D01*
Y-130000D01*
G01X251300Y-122000D02*
Y-130000D01*
G01Y-128800D02*
X250900Y-129467D01*
X250300Y-129867D01*
X249600Y-130000D01*
X248800Y-129733D01*
X248200Y-129067D01*
X247800Y-128267D01*
X247700Y-127333D01*
X247800Y-126400D01*
X248200Y-125600D01*
X248800Y-124933D01*
X249600Y-124667D01*
X250300Y-124800D01*
X250800Y-125067D01*
X251300Y-125600D01*
G01X255400Y-132400D02*
X256000Y-132667D01*
X256800Y-132400D01*
X257300Y-131867D01*
X257700Y-131200D01*
X258300Y-129067D01*
X259600Y-124667D01*
G01X256400D02*
X258300Y-129067D01*
G01X328600Y-123333D02*
X329200Y-122533D01*
X329900Y-122133D01*
X330700Y-122000D01*
X331700Y-122267D01*
X332400Y-122933D01*
X332600Y-123733D01*
X332500Y-124534D01*
X332100Y-125200D01*
X330100Y-126533D01*
X329200Y-127467D01*
X328600Y-128800D01*
X328400Y-130000D01*
X332600D01*
G01X338500Y-122000D02*
X337700Y-122267D01*
X337100Y-122933D01*
X336700Y-123733D01*
X336400Y-124800D01*
X336300Y-126000D01*
X336400Y-127200D01*
X336700Y-128267D01*
X337100Y-129067D01*
X337700Y-129733D01*
X338500Y-130000D01*
X339300Y-129733D01*
X339900Y-129067D01*
X340300Y-128267D01*
X340600Y-127200D01*
X340700Y-126000D01*
X340600Y-124800D01*
X340300Y-123733D01*
X339900Y-122933D01*
X339300Y-122267D01*
X338500Y-122000D01*
G01X346500Y-130000D02*
Y-122000D01*
X345300Y-123600D01*
G01Y-130000D02*
X347700D01*
G01X352600Y-123333D02*
X353200Y-122533D01*
X353900Y-122133D01*
X354700Y-122000D01*
X355700Y-122267D01*
X356400Y-122933D01*
X356600Y-123733D01*
X356500Y-124534D01*
X356100Y-125200D01*
X354100Y-126533D01*
X353200Y-127467D01*
X352600Y-128800D01*
X352400Y-130000D01*
X356600D01*
G01X360700Y-130267D02*
X364300Y-122000D01*
G01X370500D02*
X369700Y-122267D01*
X369100Y-122933D01*
X368700Y-123733D01*
X368400Y-124800D01*
X368300Y-126000D01*
X368400Y-127200D01*
X368700Y-128267D01*
X369100Y-129067D01*
X369700Y-129733D01*
X370500Y-130000D01*
X371300Y-129733D01*
X371900Y-129067D01*
X372300Y-128267D01*
X372600Y-127200D01*
X372700Y-126000D01*
X372600Y-124800D01*
X372300Y-123733D01*
X371900Y-122933D01*
X371300Y-122267D01*
X370500Y-122000D01*
G01X376800Y-129067D02*
X377500Y-129733D01*
X378300Y-130000D01*
X379100Y-129733D01*
X379800Y-128934D01*
X380300Y-127733D01*
X380500Y-126533D01*
Y-125067D01*
X380300Y-123867D01*
X379800Y-122800D01*
X379200Y-122267D01*
X378500Y-122000D01*
X377700Y-122267D01*
X377100Y-122800D01*
X376700Y-123600D01*
X376500Y-124667D01*
X376700Y-125600D01*
X377200Y-126533D01*
X377800Y-127067D01*
X378500Y-127200D01*
X379300Y-126934D01*
X379900Y-126267D01*
X380500Y-125067D01*
G01X384700Y-130267D02*
X388300Y-122000D01*
G01X392600Y-123333D02*
X393200Y-122533D01*
X393900Y-122133D01*
X394700Y-122000D01*
X395700Y-122267D01*
X396400Y-122933D01*
X396600Y-123733D01*
X396500Y-124534D01*
X396100Y-125200D01*
X394100Y-126533D01*
X393200Y-127467D01*
X392600Y-128800D01*
X392400Y-130000D01*
X396600D01*
G01X402500D02*
X403200Y-129867D01*
X404000Y-129467D01*
X404500Y-128800D01*
X404700Y-127867D01*
X404500Y-126934D01*
X403900Y-126133D01*
X403000Y-125733D01*
X402000D01*
X401400Y-125467D01*
X400900Y-124800D01*
X400700Y-123867D01*
X401000Y-122933D01*
X401700Y-122267D01*
X402500Y-122000D01*
X403300Y-122267D01*
X404000Y-122933D01*
X404300Y-123867D01*
X404100Y-124800D01*
X403600Y-125467D01*
X403000Y-125733D01*
X402000D01*
X401100Y-126133D01*
X400500Y-126934D01*
X400300Y-127867D01*
X400500Y-128800D01*
X401000Y-129467D01*
X401800Y-129867D01*
X402500Y-130000D01*
G01X328300Y-105000D02*
Y-97000D01*
X330300D01*
X331100Y-97400D01*
X331700Y-97933D01*
X332200Y-98733D01*
X332600Y-99667D01*
X332700Y-101000D01*
X332600Y-102333D01*
X332200Y-103267D01*
X331700Y-104067D01*
X331100Y-104600D01*
X330300Y-105000D01*
X328300D01*
G01X336000D02*
X338500Y-97000D01*
X341000Y-105000D01*
G01X340100Y-102200D02*
X336900D01*
G01X346500Y-97000D02*
X345700Y-97267D01*
X345100Y-97933D01*
X344700Y-98733D01*
X344400Y-99800D01*
X344300Y-101000D01*
X344400Y-102200D01*
X344700Y-103267D01*
X345100Y-104067D01*
X345700Y-104733D01*
X346500Y-105000D01*
X347300Y-104733D01*
X347900Y-104067D01*
X348300Y-103267D01*
X348600Y-102200D01*
X348700Y-101000D01*
X348600Y-99800D01*
X348300Y-98733D01*
X347900Y-97933D01*
X347300Y-97267D01*
X346500Y-97000D01*
G01X354500D02*
Y-105000D01*
G01X352200Y-97000D02*
X356800D01*
G01X360600Y-101667D02*
X361300Y-100733D01*
X361900Y-100200D01*
X362700Y-99933D01*
X363400Y-100200D01*
X363900Y-100733D01*
X364300Y-101533D01*
X364400Y-102467D01*
X364300Y-103267D01*
X363900Y-104067D01*
X363300Y-104733D01*
X362600Y-105000D01*
X361800Y-104733D01*
X361100Y-103934D01*
X360700Y-102733D01*
X360600Y-101400D01*
X360800Y-99667D01*
X361100Y-98733D01*
X361600Y-97800D01*
X362300Y-97133D01*
X363000Y-97000D01*
X363700Y-97267D01*
X364200Y-97933D01*
G01X367900Y-105000D02*
Y-97000D01*
X370500Y-103667D01*
X373100Y-97000D01*
Y-105000D01*
G01X378500Y-97000D02*
Y-105000D01*
G01X376200Y-97000D02*
X380800D01*
G01X387300Y-100733D02*
X387700Y-100333D01*
X388000Y-99667D01*
X388200Y-98733D01*
X388000Y-97933D01*
X387600Y-97400D01*
X386900Y-97000D01*
X384200D01*
Y-105000D01*
X387500D01*
X388200Y-104467D01*
X388600Y-103667D01*
X388800Y-102733D01*
X388600Y-101800D01*
X388000Y-101000D01*
X387300Y-100733D01*
X384200D01*
G01X394500Y-105000D02*
X395200Y-104867D01*
X396000Y-104467D01*
X396500Y-103800D01*
X396700Y-102867D01*
X396500Y-101934D01*
X395900Y-101133D01*
X395000Y-100733D01*
X394000D01*
X393400Y-100467D01*
X392900Y-99800D01*
X392700Y-98867D01*
X393000Y-97933D01*
X393700Y-97267D01*
X394500Y-97000D01*
X395300Y-97267D01*
X396000Y-97933D01*
X396300Y-98867D01*
X396100Y-99800D01*
X395600Y-100467D01*
X395000Y-100733D01*
X394000D01*
X393100Y-101133D01*
X392500Y-101934D01*
X392300Y-102867D01*
X392500Y-103800D01*
X393000Y-104467D01*
X393800Y-104867D01*
X394500Y-105000D01*
G01X400300D02*
Y-97000D01*
X402300D01*
X403100Y-97400D01*
X403700Y-97933D01*
X404200Y-98733D01*
X404600Y-99667D01*
X404700Y-101000D01*
X404600Y-102333D01*
X404200Y-103267D01*
X403700Y-104067D01*
X403100Y-104600D01*
X402300Y-105000D01*
X400300D01*
G01X410500Y-97000D02*
X409700Y-97267D01*
X409100Y-97933D01*
X408700Y-98733D01*
X408400Y-99800D01*
X408300Y-101000D01*
X408400Y-102200D01*
X408700Y-103267D01*
X409100Y-104067D01*
X409700Y-104733D01*
X410500Y-105000D01*
X411300Y-104733D01*
X411900Y-104067D01*
X412300Y-103267D01*
X412600Y-102200D01*
X412700Y-101000D01*
X412600Y-99800D01*
X412300Y-98733D01*
X411900Y-97933D01*
X411300Y-97267D01*
X410500Y-97000D01*
G01X350500Y-72000D02*
Y-80000D01*
G01X348200Y-72000D02*
X352800D01*
G01X356600Y-76667D02*
X357300Y-75733D01*
X357900Y-75200D01*
X358700Y-74933D01*
X359400Y-75200D01*
X359900Y-75733D01*
X360300Y-76533D01*
X360400Y-77467D01*
X360300Y-78267D01*
X359900Y-79067D01*
X359300Y-79733D01*
X358600Y-80000D01*
X357800Y-79733D01*
X357100Y-78934D01*
X356700Y-77733D01*
X356600Y-76400D01*
X356800Y-74667D01*
X357100Y-73733D01*
X357600Y-72800D01*
X358300Y-72133D01*
X359000Y-72000D01*
X359700Y-72267D01*
X360200Y-72933D01*
G01X363900Y-80000D02*
Y-72000D01*
X366500Y-78667D01*
X369100Y-72000D01*
Y-80000D01*
G01X371500Y-82667D02*
X377500D01*
G01X380500Y-80000D02*
Y-72000D01*
X382900D01*
X383700Y-72400D01*
X384300Y-73333D01*
X384500Y-74400D01*
X384300Y-75467D01*
X383800Y-76267D01*
X382900Y-76667D01*
X380500D01*
G01X388300Y-80000D02*
Y-72000D01*
X390300D01*
X391100Y-72400D01*
X391700Y-72933D01*
X392200Y-73733D01*
X392600Y-74667D01*
X392700Y-76000D01*
X392600Y-77333D01*
X392200Y-78267D01*
X391700Y-79067D01*
X391100Y-79600D01*
X390300Y-80000D01*
X388300D01*
G01X399300Y-75733D02*
X399700Y-75333D01*
X400000Y-74667D01*
X400200Y-73733D01*
X400000Y-72933D01*
X399600Y-72400D01*
X398900Y-72000D01*
X396200D01*
Y-80000D01*
X399500D01*
X400200Y-79467D01*
X400600Y-78667D01*
X400800Y-77733D01*
X400600Y-76800D01*
X400000Y-76000D01*
X399300Y-75733D01*
X396200D01*
G01X403500Y-82667D02*
X409500D01*
G01X412300Y-80000D02*
Y-72000D01*
X414300D01*
X415100Y-72400D01*
X415700Y-72933D01*
X416200Y-73733D01*
X416600Y-74667D01*
X416700Y-76000D01*
X416600Y-77333D01*
X416200Y-78267D01*
X415700Y-79067D01*
X415100Y-79600D01*
X414300Y-80000D01*
X412300D01*
G01X419500Y-82667D02*
X425500D01*
G01X431300Y-75733D02*
X431700Y-75333D01*
X432000Y-74667D01*
X432200Y-73733D01*
X432000Y-72933D01*
X431600Y-72400D01*
X430900Y-72000D01*
X428200D01*
Y-80000D01*
X431500D01*
X432200Y-79467D01*
X432600Y-78667D01*
X432800Y-77733D01*
X432600Y-76800D01*
X432000Y-76000D01*
X431300Y-75733D01*
X428200D01*
G01X436300Y-80000D02*
Y-72000D01*
X438300D01*
X439100Y-72400D01*
X439700Y-72933D01*
X440200Y-73733D01*
X440600Y-74667D01*
X440700Y-76000D01*
X440600Y-77333D01*
X440200Y-78267D01*
X439700Y-79067D01*
X439100Y-79600D01*
X438300Y-80000D01*
X436300D01*
G01X443300Y-130000D02*
Y-122000D01*
X445300D01*
X446100Y-122400D01*
X446700Y-122933D01*
X447200Y-123733D01*
X447600Y-124667D01*
X447700Y-126000D01*
X447600Y-127333D01*
X447200Y-128267D01*
X446700Y-129067D01*
X446100Y-129600D01*
X445300Y-130000D01*
X443300D01*
G01X473000D02*
Y-122000D01*
X471800Y-123600D01*
G01Y-130000D02*
X474200D01*
G01X478800Y-128800D02*
X479400Y-129467D01*
X480100Y-129867D01*
X481000Y-130000D01*
X481900Y-129733D01*
X482600Y-129200D01*
X483100Y-128267D01*
X483200Y-127200D01*
X483000Y-126133D01*
X482500Y-125467D01*
X481800Y-124933D01*
X481100Y-124800D01*
X480400Y-124933D01*
X479500Y-125467D01*
X479800Y-122000D01*
X482500D01*
G54D19*
X20468Y696341D03*
Y984333D03*
X20472Y1054606D03*
Y1342598D03*
G54D28*
X119920Y18071D03*
Y28071D03*
Y38071D03*
Y48071D03*
Y58071D03*
Y68071D03*
Y78071D03*
Y88071D03*
Y98071D03*
Y108071D03*
Y118071D03*
Y128071D03*
Y138071D03*
Y148071D03*
Y158071D03*
Y168071D03*
Y178071D03*
Y188071D03*
Y198071D03*
Y208071D03*
Y218071D03*
Y228071D03*
Y238071D03*
Y248071D03*
Y258071D03*
Y268071D03*
Y278071D03*
Y288071D03*
Y298071D03*
Y308071D03*
Y318071D03*
Y366102D03*
Y376102D03*
Y386102D03*
Y396102D03*
Y406102D03*
Y416102D03*
Y426102D03*
Y436102D03*
Y446102D03*
Y456102D03*
Y466102D03*
Y476102D03*
Y486102D03*
Y496102D03*
Y506102D03*
Y516102D03*
Y526102D03*
Y536102D03*
Y546102D03*
Y556102D03*
Y566102D03*
Y576102D03*
Y586102D03*
Y596102D03*
Y606102D03*
Y616102D03*
Y626102D03*
Y636102D03*
Y646102D03*
Y656102D03*
Y666102D03*
Y714134D03*
Y724134D03*
Y734134D03*
Y744134D03*
Y754134D03*
Y764134D03*
Y774134D03*
Y784134D03*
Y794134D03*
Y804134D03*
Y814134D03*
Y824134D03*
Y834134D03*
Y844134D03*
Y854134D03*
Y864134D03*
Y874134D03*
Y884134D03*
Y894134D03*
Y904134D03*
Y914134D03*
Y924134D03*
Y934134D03*
Y944134D03*
Y954134D03*
Y964134D03*
Y974134D03*
Y984134D03*
Y994134D03*
Y1004134D03*
Y1014134D03*
Y1062165D03*
Y1072165D03*
Y1082165D03*
Y1092165D03*
Y1102165D03*
Y1112165D03*
Y1122165D03*
Y1132165D03*
Y1142165D03*
Y1152165D03*
Y1162165D03*
Y1172165D03*
Y1182165D03*
Y1192165D03*
Y1202165D03*
Y1212165D03*
Y1222165D03*
Y1232165D03*
Y1242165D03*
Y1252165D03*
Y1262165D03*
Y1272165D03*
Y1282165D03*
Y1292165D03*
Y1302165D03*
Y1312165D03*
Y1322165D03*
Y1332165D03*
Y1342165D03*
Y1352165D03*
Y1362165D03*
Y1410197D03*
Y1420197D03*
Y1430197D03*
Y1440197D03*
Y1450197D03*
Y1460197D03*
Y1470197D03*
Y1480197D03*
Y1490197D03*
Y1500197D03*
Y1510197D03*
Y1520197D03*
Y1530197D03*
Y1540197D03*
Y1550197D03*
Y1560197D03*
Y1570197D03*
Y1580197D03*
Y1590197D03*
Y1600197D03*
Y1610197D03*
Y1620197D03*
Y1630197D03*
Y1640197D03*
Y1650197D03*
Y1660197D03*
Y1670197D03*
Y1680197D03*
Y1690197D03*
Y1700197D03*
Y1710197D03*
Y1758228D03*
Y1768228D03*
Y1778228D03*
Y1788228D03*
Y1798228D03*
Y1808228D03*
Y1818228D03*
Y1828228D03*
Y1838228D03*
Y1848228D03*
Y1858228D03*
Y1868228D03*
Y1878228D03*
Y1888228D03*
Y1898228D03*
Y1908228D03*
Y1918228D03*
Y1928228D03*
Y1938228D03*
Y1948228D03*
Y1958228D03*
Y1968228D03*
Y1978228D03*
Y1988228D03*
Y1998228D03*
Y2008228D03*
Y2018228D03*
Y2028228D03*
Y2038228D03*
Y2048228D03*
Y2058228D03*
X139920Y28071D03*
Y18071D03*
Y58071D03*
Y48071D03*
Y38071D03*
Y78071D03*
Y68071D03*
Y98071D03*
Y88071D03*
Y128071D03*
Y118071D03*
Y108071D03*
Y148071D03*
Y138071D03*
Y178071D03*
Y168071D03*
Y158071D03*
Y198071D03*
Y188071D03*
Y228071D03*
Y218071D03*
Y208071D03*
Y248071D03*
Y238071D03*
Y268071D03*
Y258071D03*
Y298071D03*
Y288071D03*
Y278071D03*
Y318071D03*
Y308071D03*
Y328071D03*
Y366102D03*
Y396102D03*
Y386102D03*
Y376102D03*
Y416102D03*
Y406102D03*
Y436102D03*
Y426102D03*
Y466102D03*
Y456102D03*
Y446102D03*
Y486102D03*
Y476102D03*
Y516102D03*
Y506102D03*
Y496102D03*
Y536102D03*
Y526102D03*
Y566102D03*
Y556102D03*
Y546102D03*
Y586102D03*
Y576102D03*
Y606102D03*
Y596102D03*
Y636102D03*
Y626102D03*
Y616102D03*
Y656102D03*
Y646102D03*
Y676102D03*
Y666102D03*
Y734134D03*
Y724134D03*
Y714134D03*
Y754134D03*
Y744134D03*
Y774134D03*
Y764134D03*
Y804134D03*
Y794134D03*
Y784134D03*
Y824134D03*
Y814134D03*
Y854134D03*
Y844134D03*
Y834134D03*
Y874134D03*
Y864134D03*
Y904134D03*
Y894134D03*
Y884134D03*
Y924134D03*
Y914134D03*
Y944134D03*
Y934134D03*
Y974134D03*
Y964134D03*
Y954134D03*
Y994134D03*
Y984134D03*
Y1024134D03*
Y1014134D03*
Y1004134D03*
Y1072165D03*
Y1062165D03*
Y1092165D03*
Y1082165D03*
Y1122165D03*
Y1112165D03*
Y1102165D03*
Y1142165D03*
Y1132165D03*
Y1162165D03*
Y1152165D03*
Y1192165D03*
Y1182165D03*
Y1172165D03*
Y1212165D03*
Y1202165D03*
Y1242165D03*
Y1232165D03*
Y1222165D03*
Y1262165D03*
Y1252165D03*
Y1282165D03*
Y1272165D03*
Y1312165D03*
Y1302165D03*
Y1292165D03*
Y1332165D03*
Y1322165D03*
Y1362165D03*
Y1352165D03*
Y1342165D03*
Y1372165D03*
Y1410197D03*
Y1430197D03*
Y1420197D03*
Y1460197D03*
Y1450197D03*
Y1440197D03*
Y1480197D03*
Y1470197D03*
Y1500197D03*
Y1490197D03*
Y1530197D03*
Y1520197D03*
Y1510197D03*
Y1550197D03*
Y1540197D03*
Y1580197D03*
Y1570197D03*
Y1560197D03*
Y1600197D03*
Y1590197D03*
Y1620197D03*
Y1610197D03*
Y1650197D03*
Y1640197D03*
Y1630197D03*
Y1670197D03*
Y1660197D03*
Y1700197D03*
Y1690197D03*
Y1680197D03*
Y1720197D03*
Y1710197D03*
Y1768228D03*
Y1758228D03*
Y1798228D03*
Y1788228D03*
Y1778228D03*
Y1818228D03*
Y1808228D03*
Y1838228D03*
Y1828228D03*
Y1868228D03*
Y1858228D03*
Y1848228D03*
Y1888228D03*
Y1878228D03*
Y1918228D03*
Y1908228D03*
Y1898228D03*
Y1938228D03*
Y1928228D03*
Y1958228D03*
Y1948228D03*
Y1988228D03*
Y1978228D03*
Y1968228D03*
Y2008228D03*
Y1998228D03*
Y2038228D03*
Y2028228D03*
Y2018228D03*
Y2058228D03*
Y2048228D03*
Y2068228D03*
G54D29*
X119920Y328071D03*
Y676102D03*
Y1024134D03*
Y1372165D03*
Y1720197D03*
Y2068228D03*
M02*
